# TIMECARD (Time Appliance Project (Time Card)) — schematic netlist excerpt (pin names and nets, part order shuffled) for the footprints in the layout excerpt that follows; sources: Cadence DE-HDL packaged netlist, KiCad conversion of R4006-B0001-02_R01.brd

SP70  NULL  pkg DUMMY  page 34
R156  RESISTOR  100OHM 1%  pkg SMC_0402R_H016  page 23 : \1\ = ANT3_OUT ; \2\ = UNNAMED_12_74HCT2G125DPTSSOP8_I
SP51  NULL  pkg DUMMY  page 34
R397  RESISTOR  33OHM 1%  pkg SMC_0402R_H016  page 26 : \1\ = GPS_SMA_LED_BLUE_N ; \2\ = UNNAMED_14_LED4PV14_I269_1

(kicad_pcb
	(version 20260206)
	(generator "pcbnew")
	(generator_version "10.0")
	(general
		(thickness 1.6)
		(legacy_teardrops no)
	)
	(paper "A4")
	(title_block
		(title "timecard-production-celestica-r4006 — R4006-B0001-02_R01.brd")
		(comment 1 "Time Appliance Project (Time Card) / footprints 45-48 of 1113")
	)
	(layers
		(0 "F.Cu" signal "TOP")
		(4 "In1.Cu" signal "L02_GND1")
		(6 "In2.Cu" signal "L03_SIG1")
		(8 "In3.Cu" signal "L04_GND2")
		(10 "In4.Cu" signal "L05_VCC1")
		(12 "In5.Cu" signal "L06_VCC2")
		(14 "In6.Cu" signal "L07_GND3")
		(16 "In7.Cu" signal "L08_SIG2")
		(18 "In8.Cu" signal "L09_GND4")
		(2 "B.Cu" signal "BOTTOM")
		(9 "F.Adhes" user "F.Adhesive")
		(11 "B.Adhes" user "B.Adhesive")
		(13 "F.Paste" user "Package Geometry/Pastemask Top")
		(15 "B.Paste" user "Package Geometry/Pastemask Bottom")
		(5 "F.SilkS" user "Ref Des/Silkscreen Top")
		(7 "B.SilkS" user "Ref Des/Silkscreen Bottom")
		(1 "F.Mask" user "Board Geometry/Soldermask Top")
		(3 "B.Mask" user "Board Geometry/Soldermask Bottom")
		(17 "Dwgs.User" user "User.Drawings")
		(19 "Cmts.User" user "User.Comments")
		(21 "Eco1.User" user "User.Eco1")
		(23 "Eco2.User" user "User.Eco2")
		(25 "Edge.Cuts" user "Board Geometry/Outline")
		(27 "Margin" user)
		(31 "F.CrtYd" user "Package Geometry/Place Bound Top")
		(29 "B.CrtYd" user "Package Geometry/Place Bound Bottom")
		(35 "F.Fab" user "Ref Des/Assembly Top")
		(33 "B.Fab" user "Ref Des/Assembly Bottom")
	)
	(footprint ""
		(layer "F.Cu")
		(at 13.462 -37.211 -90)
		(property "Reference" "R156"
			(at 1.27 3.51663 90)
			(unlocked yes)
			(layer "F.SilkS")
			(effects
				(font
					(size 0.7874 0.5842)
					(thickness 0.1524)
				)
			)
		)
		(property "Value" "VAL*"
			(at 0.02032 2.13233 270)
			(unlocked yes)
			(layer "F.Fab")
			(hide yes)
			(effects
				(font
					(size 0.7874 0.5842)
					(thickness 0.1524)
				)
			)
		)
		(property "Tolerance" "TOL*"
			(at 0.044704 3.05435 270)
			(unlocked yes)
			(layer "Cmts.User")
			(hide yes)
			(effects
				(font
					(size 0.7874 0.5842)
					(thickness 0.1524)
				)
			)
		)
		(property "User Part Number" "PARTNUM*"
			(at 0.02032 4.024884 270)
			(unlocked yes)
			(layer "Cmts.User")
			(hide yes)
			(effects
				(font
					(size 0.7874 0.5842)
					(thickness 0.1524)
				)
			)
		)
		(property "Device Type" "RESISTOR-G155-11000-01,100OHM,A"
			(at 0.008382 1.210564 270)
			(unlocked yes)
			(layer "F.Fab")
			(hide yes)
			(effects
				(font
					(size 0.7874 0.5842)
					(thickness 0.1524)
				)
			)
		)
		(duplicate_pad_numbers_are_jumpers no)
		(fp_line
			(start -1.143 0.5588)
			(end 1.143 0.5588)
			(stroke
				(width 0.1)
				(type default)
			)
			(layer "F.SilkS")
		)
		(fp_line
			(start 1.143 0.5588)
			(end 1.143 -0.5588)
			(stroke
				(width 0.1)
				(type default)
			)
			(layer "F.SilkS")
		)
		(fp_line
			(start -1.143 -0.5588)
			(end -1.143 0.5588)
			(stroke
				(width 0.1)
				(type default)
			)
			(layer "F.SilkS")
		)
		(fp_line
			(start 1.143 -0.5588)
			(end -1.143 -0.5588)
			(stroke
				(width 0.1)
				(type default)
			)
			(layer "F.SilkS")
		)
		(fp_poly
			(pts
				(xy -1.143 0.5588) (xy 1.143 0.5588) (xy 1.143 -0.5588) (xy -1.143 -0.5588)
			)
			(stroke
				(width 0)
				(type default)
			)
			(fill no)
			(layer "F.CrtYd")
		)
		(fp_line
			(start -0.508 0.3048)
			(end 0.508 0.3048)
			(stroke
				(width 0.1)
				(type default)
			)
			(layer "F.Fab")
		)
		(fp_line
			(start 0.508 0.3048)
			(end 0.508 -0.3048)
			(stroke
				(width 0.1)
				(type default)
			)
			(layer "F.Fab")
		)
		(fp_line
			(start -0.508 -0.3048)
			(end -0.508 0.3048)
			(stroke
				(width 0.1)
				(type default)
			)
			(layer "F.Fab")
		)
		(fp_line
			(start 0.508 -0.3048)
			(end -0.508 -0.3048)
			(stroke
				(width 0.1)
				(type default)
			)
			(layer "F.Fab")
		)
		(pad "1" smd rect
			(at -0.5334 0 270)
			(size 0.7112 0.6096)
			(layers "F.Cu" "F.Mask" "F.Paste")
			(net "ANT3_OUT")
		)
		(pad "2" smd rect
			(at 0.5334 0 270)
			(size 0.7112 0.6096)
			(layers "F.Cu" "F.Mask" "F.Paste")
			(net "UNNAMED_12_74HCT2G125DPTSSOP8_I")
		)
		(zone
			(layer "F.Cu")
			(hatch none 0.5)
			(connect_pads
				(clearance 0)
			)
			(min_thickness 0.25)
			(keepout
				(tracks not_allowed)
				(vias allowed)
				(pads allowed)
				(copperpour not_allowed)
				(footprints allowed)
			)
			(placement
				(enabled no)
				(sheetname "")
			)
			(fill
				(thermal_gap 0.5)
				(thermal_bridge_width 0.5)
				(island_removal_mode 0)
			)
			(polygon
				(pts
					(xy 13.1572 -37.2872) (xy 13.1572 -37.1348) (xy 13.7668 -37.1348) (xy 13.7668 -37.2872)
				)
			)
		)
		(zone
			(layer "F.Cu")
			(hatch none 0.5)
			(connect_pads
				(clearance 0)
			)
			(min_thickness 0.25)
			(keepout
				(tracks allowed)
				(vias not_allowed)
				(pads allowed)
				(copperpour not_allowed)
				(footprints allowed)
			)
			(placement
				(enabled no)
				(sheetname "")
			)
			(fill
				(thermal_gap 0.5)
				(thermal_bridge_width 0.5)
				(island_removal_mode 0)
			)
			(polygon
				(pts
					(xy 13.1572 -37.2872) (xy 13.1572 -37.1348) (xy 13.7668 -37.1348) (xy 13.7668 -37.2872)
				)
			)
		)
	)
	(footprint ""
		(layer "F.Cu")
		(at 55.88 -131.064)
		(property "Reference" "SP70"
			(at 0 0 0)
			(layer "F.SilkS")
			(hide yes)
			(effects
				(font
					(size 1.27 1.27)
				)
			)
		)
		(property "Value" ""
			(at 0 0 0)
			(layer "F.Fab")
			(effects
				(font
					(size 1.27 1.27)
				)
			)
		)
		(duplicate_pad_numbers_are_jumpers no)
	)
	(footprint ""
		(layer "F.Cu")
		(at 54.102 -130.429)
		(property "Reference" "SP51"
			(at 0 0 0)
			(layer "F.SilkS")
			(hide yes)
			(effects
				(font
					(size 1.27 1.27)
				)
			)
		)
		(property "Value" ""
			(at 0 0 0)
			(layer "F.Fab")
			(effects
				(font
					(size 1.27 1.27)
				)
			)
		)
		(duplicate_pad_numbers_are_jumpers no)
	)
	(footprint ""
		(layer "F.Cu")
		(at 4.572 -81.534 90)
		(property "Reference" "R397"
			(at -2.667 -0.97663 90)
			(unlocked yes)
			(layer "F.SilkS")
			(effects
				(font
					(size 0.7874 0.5842)
					(thickness 0.1524)
				)
			)
		)
		(property "Value" "VAL*"
			(at 0.02032 2.13233 90)
			(unlocked yes)
			(layer "F.Fab")
			(hide yes)
			(effects
				(font
					(size 0.7874 0.5842)
					(thickness 0.1524)
				)
			)
		)
		(property "Tolerance" "TOL*"
			(at 0.044704 3.05435 90)
			(unlocked yes)
			(layer "Cmts.User")
			(hide yes)
			(effects
				(font
					(size 0.7874 0.5842)
					(thickness 0.1524)
				)
			)
		)
		(property "User Part Number" "PARTNUM*"
			(at 0.02032 4.024884 90)
			(unlocked yes)
			(layer "Cmts.User")
			(hide yes)
			(effects
				(font
					(size 0.7874 0.5842)
					(thickness 0.1524)
				)
			)
		)
		(property "Device Type" "RESISTOR-G155-133R0-01,33OHM,1%"
			(at 0.008382 1.210564 90)
			(unlocked yes)
			(layer "F.Fab")
			(hide yes)
			(effects
				(font
					(size 0.7874 0.5842)
					(thickness 0.1524)
				)
			)
		)
		(duplicate_pad_numbers_are_jumpers no)
		(fp_line
			(start 1.143 -0.5588)
			(end -1.143 -0.5588)
			(stroke
				(width 0.1)
				(type default)
			)
			(layer "F.SilkS")
		)
		(fp_line
			(start -1.143 -0.5588)
			(end -1.143 0.5588)
			(stroke
				(width 0.1)
				(type default)
			)
			(layer "F.SilkS")
		)
		(fp_line
			(start 1.143 0.5588)
			(end 1.143 -0.5588)
			(stroke
				(width 0.1)
				(type default)
			)
			(layer "F.SilkS")
		)
		(fp_line
			(start -1.143 0.5588)
			(end 1.143 0.5588)
			(stroke
				(width 0.1)
				(type default)
			)
			(layer "F.SilkS")
		)
		(fp_rect
			(start -1.143 -0.5588)
			(end 1.143 0.5588)
			(stroke
				(width 0)
				(type default)
			)
			(fill no)
			(layer "F.CrtYd")
		)
		(fp_line
			(start 0.508 -0.3048)
			(end -0.508 -0.3048)
			(stroke
				(width 0.1)
				(type default)
			)
			(layer "F.Fab")
		)
		(fp_line
			(start -0.508 -0.3048)
			(end -0.508 0.3048)
			(stroke
				(width 0.1)
				(type default)
			)
			(layer "F.Fab")
		)
		(fp_line
			(start 0.508 0.3048)
			(end 0.508 -0.3048)
			(stroke
				(width 0.1)
				(type default)
			)
			(layer "F.Fab")
		)
		(fp_line
			(start -0.508 0.3048)
			(end 0.508 0.3048)
			(stroke
				(width 0.1)
				(type default)
			)
			(layer "F.Fab")
		)
		(pad "1" smd rect
			(at -0.5334 0 90)
			(size 0.7112 0.6096)
			(layers "F.Cu" "F.Mask" "F.Paste")
			(net "GPS_SMA_LED_BLUE_N")
		)
		(pad "2" smd rect
			(at 0.5334 0 90)
			(size 0.7112 0.6096)
			(layers "F.Cu" "F.Mask" "F.Paste")
			(net "UNNAMED_14_LED4PV14_I269_1")
		)
		(zone
			(layer "F.Cu")
			(hatch none 0.5)
			(connect_pads
				(clearance 0)
			)
			(min_thickness 0.25)
			(keepout
				(tracks not_allowed)
				(vias allowed)
				(pads allowed)
				(copperpour not_allowed)
				(footprints allowed)
			)
			(placement
				(enabled no)
				(sheetname "")
			)
			(fill
				(thermal_gap 0.5)
				(thermal_bridge_width 0.5)
				(island_removal_mode 0)
			)
			(polygon
				(pts
					(xy 4.2672 -81.4578) (xy 4.8768 -81.4578) (xy 4.8768 -81.6102) (xy 4.2672 -81.6102)
				)
			)
		)
		(zone
			(layer "F.Cu")
			(hatch none 0.5)
			(connect_pads
				(clearance 0)
			)
			(min_thickness 0.25)
			(keepout
				(tracks allowed)
				(vias not_allowed)
				(pads allowed)
				(copperpour not_allowed)
				(footprints allowed)
			)
			(placement
				(enabled no)
				(sheetname "")
			)
			(fill
				(thermal_gap 0.5)
				(thermal_bridge_width 0.5)
				(island_removal_mode 0)
			)
			(polygon
				(pts
					(xy 4.2672 -81.4578) (xy 4.8768 -81.4578) (xy 4.8768 -81.6102) (xy 4.2672 -81.6102)
				)
			)
		)
	)
)
